(kicad_pcb
	(version 20241229)
	(generator "pcbnew")
	(generator_version "9.0")
	(general
		(thickness 1.294)
		(legacy_teardrops no)
	)
	(paper "A3")
	(title_block
		(title "Kintex 410T devboard")
		(date "2024-04-03")
		(rev "1.1.2")
		(comment 9 "footprints 475-479 of 975")
	)
	(layers
		(0 "F.Cu" mixed)
		(4 "In1.Cu" power)
		(6 "In2.Cu" power)
		(8 "In3.Cu" mixed)
		(10 "In4.Cu" power)
		(12 "In5.Cu" mixed)
		(14 "In6.Cu" power)
		(16 "In7.Cu" mixed)
		(18 "In8.Cu" power)
		(2 "B.Cu" mixed)
		(9 "F.Adhes" user "F.Adhesive")
		(11 "B.Adhes" user "B.Adhesive")
		(13 "F.Paste" user)
		(15 "B.Paste" user)
		(5 "F.SilkS" user "F.Silkscreen")
		(7 "B.SilkS" user "B.Silkscreen")
		(1 "F.Mask" user)
		(3 "B.Mask" user)
		(17 "Dwgs.User" user "User.Drawings")
		(19 "Cmts.User" user "User.Comments")
		(21 "Eco1.User" user "User.Eco1")
		(23 "Eco2.User" user "User.Eco2")
		(25 "Edge.Cuts" user)
		(27 "Margin" user)
		(31 "F.CrtYd" user "F.Courtyard")
		(29 "B.CrtYd" user "B.Courtyard")
		(35 "F.Fab" user)
		(33 "B.Fab" user)
	)
	(footprint "antmicro-footprints:R_0402_1005Metric"
		(layer "F.Cu")
		(at 250.899 96 180)
		(descr "Resistor SMD 0402")
		(tags "resistor SMD 0402")
		(property "Reference" "R342"
			(at 1.399 1.6 0)
			(layer "F.SilkS")
			(effects
				(font
					(size 0.7 0.7)
					(thickness 0.15)
				)
				(justify left bottom)
			)
		)
		(property "Value" "R_0R_0402"
			(at 0 1.4 180)
			(layer "F.Fab")
			(effects
				(font
					(size 0.7 0.7)
					(thickness 0.15)
				)
				(justify left bottom)
			)
		)
		(property "Description" "SMD Chip Resistor, Jumper, 0 ohm, 100 mW, 0402 [1005 Metric], Thick Film, General Purpose"
			(at 0 0 180)
			(layer "F.Fab")
			(hide yes)
			(effects
				(font
					(size 1.27 1.27)
					(thickness 0.15)
				)
			)
		)
		(property "Author" "Antmicro"
			(at 501.798 192 0)
			(layer "F.Fab")
			(hide yes)
			(effects
				(font
					(size 1 1)
					(thickness 0.15)
				)
			)
		)
		(property "Current" "1A"
			(at 501.798 192 0)
			(layer "F.Fab")
			(hide yes)
			(effects
				(font
					(size 1 1)
					(thickness 0.15)
				)
			)
		)
		(property "DNP" "DNP"
			(at 501.798 192 0)
			(layer "F.Fab")
			(hide yes)
			(effects
				(font
					(size 1 1)
					(thickness 0.15)
				)
			)
		)
		(property "License" "Apache-2.0"
			(at 501.798 192 0)
			(layer "F.Fab")
			(hide yes)
			(effects
				(font
					(size 1 1)
					(thickness 0.15)
				)
			)
		)
		(property "MPN" "ERJ2GE0R00X"
			(at 501.798 192 0)
			(layer "F.Fab")
			(hide yes)
			(effects
				(font
					(size 1 1)
					(thickness 0.15)
				)
			)
		)
		(property "Manufacturer" "Panasonic"
			(at 501.798 192 0)
			(layer "F.Fab")
			(hide yes)
			(effects
				(font
					(size 1 1)
					(thickness 0.15)
				)
			)
		)
		(property "Tolerance" ""
			(at 501.798 192 0)
			(layer "F.Fab")
			(hide yes)
			(effects
				(font
					(size 1 1)
					(thickness 0.15)
				)
			)
		)
		(property "Val" "0R"
			(at 501.798 192 0)
			(layer "F.Fab")
			(hide yes)
			(effects
				(font
					(size 1 1)
					(thickness 0.15)
				)
			)
		)
		(property "dnp" ""
			(at 501.798 192 0)
			(layer "F.Fab")
			(hide yes)
			(effects
				(font
					(size 1 1)
					(thickness 0.15)
				)
			)
		)
		(property "exclude_from_bom" ""
			(at 501.798 192 0)
			(layer "F.Fab")
			(hide yes)
			(effects
				(font
					(size 1 1)
					(thickness 0.15)
				)
			)
		)
		(sheetname "USB PHY")
		(sheetfile "usb-phy.kicad_sch")
		(attr smd exclude_from_bom)
		(fp_rect
			(start -0.925 -0.47)
			(end 0.925 0.47)
			(stroke
				(width 0.05)
				(type default)
			)
			(fill no)
			(layer "F.CrtYd")
		)
		(fp_rect
			(start -0.5 -0.25)
			(end 0.5 0.25)
			(stroke
				(width 0.15)
				(type solid)
			)
			(fill no)
			(layer "F.Fab")
		)
		(pad "1" smd roundrect
			(at -0.48 0 180)
			(size 0.59 0.64)
			(layers "F.Cu" "F.Mask" "F.Paste")
			(roundrect_rratio 0.25)
			(net 703 "+5V")
			(pintype "passive")
		)
		(pad "2" smd roundrect
			(at 0.48 0 180)
			(size 0.59 0.64)
			(layers "F.Cu" "F.Mask" "F.Paste")
			(roundrect_rratio 0.25)
			(net 583 "/USB PHY/USB_HOST_VBUS_EN")
			(pintype "passive")
		)
	)
	(footprint "antmicro-footprints:Vishay_PowerPAK_1212-8_Single"
		(layer "F.Cu")
		(at 225.8 157.2 180)
		(descr "PowerPAK 1212-8 Single")
		(tags "Vishay PowerPAK 1212-8 Single")
		(property "Reference" "Q4"
			(at -0.35 1.95 180)
			(layer "F.SilkS")
			(effects
				(font
					(size 0.7 0.7)
					(thickness 0.15)
				)
				(justify left bottom)
			)
		)
		(property "Value" "SI7613DN-T1-GE3"
			(at -8 2.7 180)
			(layer "F.Fab")
			(effects
				(font
					(size 0.7 0.7)
					(thickness 0.15)
				)
				(justify left bottom)
			)
		)
		(property "Description" "Power MOSFET, P Channel, 20 V, 35 A, 0.0072 ohm, PowerPAK 1212, Surface Mount"
			(at 0 0 180)
			(layer "F.Fab")
			(hide yes)
			(effects
				(font
					(size 1.27 1.27)
					(thickness 0.15)
				)
			)
		)
		(property "Author" "Antmicro"
			(at 451.6 314.4 0)
			(layer "F.Fab")
			(hide yes)
			(effects
				(font
					(size 1 1)
					(thickness 0.15)
				)
			)
		)
		(property "License" "Apache-2.0"
			(at 451.6 314.4 0)
			(layer "F.Fab")
			(hide yes)
			(effects
				(font
					(size 1 1)
					(thickness 0.15)
				)
			)
		)
		(property "MPN" "SI7613DN-T1-GE3"
			(at 451.6 314.4 0)
			(layer "F.Fab")
			(hide yes)
			(effects
				(font
					(size 1 1)
					(thickness 0.15)
				)
			)
		)
		(property "Manufacturer" "Vishay"
			(at 451.6 314.4 0)
			(layer "F.Fab")
			(hide yes)
			(effects
				(font
					(size 1 1)
					(thickness 0.15)
				)
			)
		)
		(sheetname "Power supply")
		(sheetfile "power-supply.kicad_sch")
		(attr smd)
		(fp_line
			(start 1.648 -1.651)
			(end 1.648 -1.317)
			(stroke
				(width 0.15)
				(type solid)
			)
			(layer "F.SilkS")
		)
		(fp_line
			(start 1.634 1.3)
			(end 1.634 1.634)
			(stroke
				(width 0.15)
				(type solid)
			)
			(layer "F.SilkS")
		)
		(fp_line
			(start -1.635 1.634)
			(end 1.634 1.634)
			(stroke
				(width 0.15)
				(type solid)
			)
			(layer "F.SilkS")
		)
		(fp_line
			(start -1.635 1.3)
			(end -1.635 1.634)
			(stroke
				(width 0.15)
				(type solid)
			)
			(layer "F.SilkS")
		)
		(fp_line
			(start -1.651 -1.651)
			(end 1.648 -1.651)
			(stroke
				(width 0.15)
				(type solid)
			)
			(layer "F.SilkS")
		)
		(fp_line
			(start -1.651 -1.651)
			(end -1.651 -1.317)
			(stroke
				(width 0.15)
				(type solid)
			)
			(layer "F.SilkS")
		)
		(fp_circle
			(center -1.9 -1.4)
			(end -1.85 -1.4)
			(stroke
				(width 0.15)
				(type solid)
			)
			(fill yes)
			(layer "F.SilkS")
		)
		(fp_rect
			(start -2 -1.8)
			(end 2 1.798)
			(stroke
				(width 0.05)
				(type solid)
			)
			(fill no)
			(layer "F.CrtYd")
		)
		(fp_line
			(start -1.6425 -1.4175)
			(end -1.4175 -1.6425)
			(stroke
				(width 0.15)
				(type solid)
			)
			(layer "F.Fab")
		)
		(fp_rect
			(start -1.651 -1.651)
			(end 1.648 1.648)
			(stroke
				(width 0.15)
				(type solid)
			)
			(fill no)
			(layer "F.Fab")
		)
		(pad "1" smd rect
			(at -1.436 -0.99 180)
			(size 0.99 0.405)
			(layers "F.Cu" "F.Mask" "F.Paste")
			(net 5 "/Power supply/PD_VBUS")
			(pinfunction "S")
			(pintype "passive")
		)
		(pad "2" smd rect
			(at -1.436 -0.332 180)
			(size 0.99 0.405)
			(layers "F.Cu" "F.Mask" "F.Paste")
			(net 5 "/Power supply/PD_VBUS")
			(pinfunction "S")
			(pintype "passive")
		)
		(pad "3" smd rect
			(at -1.436 0.33 180)
			(size 0.99 0.405)
			(layers "F.Cu" "F.Mask" "F.Paste")
			(net 5 "/Power supply/PD_VBUS")
			(pinfunction "S")
			(pintype "passive")
		)
		(pad "4" smd rect
			(at -1.436 0.988 180)
			(size 0.99 0.405)
			(layers "F.Cu" "F.Mask" "F.Paste")
			(net 872 "/Power supply/SINK_EN")
			(pinfunction "G")
			(pintype "passive")
		)
		(pad "5" smd custom
			(at 0.557 0 180)
			(size 1.725 2.235)
			(layers "F.Cu" "F.Mask" "F.Paste")
			(net 700 "/Power supply/USB_PD_VBUS")
			(pinfunction "D")
			(pintype "passive")
			(zone_connect 2)
			(options
				(clearance outline)
				(anchor rect)
			)
			(primitives
				(gr_poly
					(pts
						(xy 0.8625 0.1275) (xy 0.8625 -0.1275) (xy 1.3725 -0.1275) (xy 1.3725 -0.5325) (xy 0.8625 -0.5325)
						(xy 0.8625 -0.7875) (xy 1.3725 -0.7875) (xy 1.3725 -1.195) (xy 0.6125 -1.195) (xy 0.6125 1.195)
						(xy 1.3725 1.195) (xy 1.3725 0.7875) (xy 0.8625 0.7875) (xy 0.8625 0.5325) (xy 1.3725 0.5325)
						(xy 1.3725 0.1275)
					)
					(width 0)
					(fill yes)
				)
			)
		)
	)
	(footprint "antmicro-footprints:TP_SMD_0.75mm"
		(layer "F.Cu")
		(at 172.66 81.1308 180)
		(property "Reference" "TP3"
			(at -0.34 0.3308 270)
			(layer "F.SilkS")
			(effects
				(font
					(size 0.7 0.7)
					(thickness 0.15)
				)
				(justify left bottom)
			)
		)
		(property "Value" "TP_0.75mm_SMD"
			(at 0 1.2 180)
			(layer "F.Fab")
			(effects
				(font
					(size 0.7 0.7)
					(thickness 0.15)
				)
				(justify left bottom)
			)
		)
		(property "Description" "SMT test point"
			(at 0 0 180)
			(layer "F.Fab")
			(hide yes)
			(effects
				(font
					(size 1.27 1.27)
					(thickness 0.15)
				)
			)
		)
		(property "Author" "Antmicro"
			(at 345.32 162.2616 0)
			(layer "F.Fab")
			(hide yes)
			(effects
				(font
					(size 1 1)
					(thickness 0.15)
				)
			)
		)
		(property "License" "Apache-2.0"
			(at 345.32 162.2616 0)
			(layer "F.Fab")
			(hide yes)
			(effects
				(font
					(size 1 1)
					(thickness 0.15)
				)
			)
		)
		(property "MPN" ""
			(at 345.32 162.2616 0)
			(layer "F.Fab")
			(hide yes)
			(effects
				(font
					(size 1 1)
					(thickness 0.15)
				)
			)
		)
		(property "Manufacturer" ""
			(at 345.32 162.2616 0)
			(layer "F.Fab")
			(hide yes)
			(effects
				(font
					(size 1 1)
					(thickness 0.15)
				)
			)
		)
		(sheetname "FMC+ HSPC")
		(sheetfile "fmc-hspc.kicad_sch")
		(attr exclude_from_pos_files)
		(pad "1" smd circle
			(at 0 0 180)
			(size 0.75 0.75)
			(layers "F.Cu" "F.Mask")
			(net 153 "Net-(J18B-PG_M2C)")
			(pinfunction "1")
			(pintype "passive")
		)
	)
	(footprint "antmicro-footprints:SC70-3"
		(layer "F.Cu")
		(at 258.4 86.2)
		(property "Reference" "Q9"
			(at -1.6 1.1 90)
			(layer "F.SilkS")
			(effects
				(font
					(size 0.7 0.7)
					(thickness 0.15)
				)
				(justify left bottom)
			)
		)
		(property "Value" "BSS138PW"
			(at 0 2.3 0)
			(layer "F.Fab")
			(effects
				(font
					(size 0.7 0.7)
					(thickness 0.15)
				)
				(justify left bottom)
			)
		)
		(property "Description" "Power MOSFET, N Channel, 60 V, 320 mA, 0.9 ohm, SOT-323, Surface Mount"
			(at 0 0 0)
			(layer "F.Fab")
			(hide yes)
			(effects
				(font
					(size 1.27 1.27)
					(thickness 0.15)
				)
			)
		)
		(property "Author" "Antmicro"
			(at 0 0 0)
			(layer "F.Fab")
			(hide yes)
			(effects
				(font
					(size 1 1)
					(thickness 0.15)
				)
			)
		)
		(property "License" "Apache-2.0"
			(at 0 0 0)
			(layer "F.Fab")
			(hide yes)
			(effects
				(font
					(size 1 1)
					(thickness 0.15)
				)
			)
		)
		(property "MPN" "BSS138PW"
			(at 0 0 0)
			(layer "F.Fab")
			(hide yes)
			(effects
				(font
					(size 1 1)
					(thickness 0.15)
				)
			)
		)
		(property "Manufacturer" "Nexperia"
			(at 0 0 0)
			(layer "F.Fab")
			(hide yes)
			(effects
				(font
					(size 1 1)
					(thickness 0.15)
				)
			)
		)
		(sheetname "User GPIO + LED + button + DIP switch")
		(sheetfile "user-gpio.kicad_sch")
		(attr smd)
		(fp_line
			(start -0.3 -1)
			(end 0.627 -0.999)
			(stroke
				(width 0.15)
				(type solid)
			)
			(layer "F.SilkS")
		)
		(fp_line
			(start -0.3 1)
			(end 0.627 1.001)
			(stroke
				(width 0.15)
				(type solid)
			)
			(layer "F.SilkS")
		)
		(fp_line
			(start 0.627 -0.6)
			(end 0.627 -0.999)
			(stroke
				(width 0.15)
				(type solid)
			)
			(layer "F.SilkS")
		)
		(fp_line
			(start 0.627 0.6)
			(end 0.627 1.001)
			(stroke
				(width 0.15)
				(type solid)
			)
			(layer "F.SilkS")
		)
		(fp_line
			(start -1.4 1)
			(end -1.4 -1)
			(stroke
				(width 0.05)
				(type solid)
			)
			(layer "F.CrtYd")
		)
		(fp_line
			(start -0.9 -1.3)
			(end -0.9 -1)
			(stroke
				(width 0.05)
				(type solid)
			)
			(layer "F.CrtYd")
		)
		(fp_line
			(start -0.9 -1.3)
			(end 0.9 -1.3)
			(stroke
				(width 0.05)
				(type solid)
			)
			(layer "F.CrtYd")
		)
		(fp_line
			(start -0.9 -1)
			(end -1.4 -1)
			(stroke
				(width 0.05)
				(type solid)
			)
			(layer "F.CrtYd")
		)
		(fp_line
			(start -0.9 1)
			(end -1.4 1)
			(stroke
				(width 0.05)
				(type solid)
			)
			(layer "F.CrtYd")
		)
		(fp_line
			(start -0.9 1.3)
			(end -0.9 1)
			(stroke
				(width 0.05)
				(type solid)
			)
			(layer "F.CrtYd")
		)
		(fp_line
			(start 0.9 -1.3)
			(end 0.9 -0.4)
			(stroke
				(width 0.05)
				(type solid)
			)
			(layer "F.CrtYd")
		)
		(fp_line
			(start 0.9 -0.4)
			(end 1.4 -0.4)
			(stroke
				(width 0.05)
				(type solid)
			)
			(layer "F.CrtYd")
		)
		(fp_line
			(start 0.9 0.4)
			(end 0.9 1.3)
			(stroke
				(width 0.05)
				(type solid)
			)
			(layer "F.CrtYd")
		)
		(fp_line
			(start 0.9 1.3)
			(end -0.9 1.3)
			(stroke
				(width 0.05)
				(type solid)
			)
			(layer "F.CrtYd")
		)
		(fp_line
			(start 1.4 -0.4)
			(end 1.4 0.4)
			(stroke
				(width 0.05)
				(type solid)
			)
			(layer "F.CrtYd")
		)
		(fp_line
			(start 1.4 0.4)
			(end 0.9 0.4)
			(stroke
				(width 0.05)
				(type solid)
			)
			(layer "F.CrtYd")
		)
		(fp_rect
			(start -0.623 -0.999)
			(end 0.627 1.001)
			(stroke
				(width 0.15)
				(type solid)
			)
			(fill no)
			(layer "F.Fab")
		)
		(pad "1" smd rect
			(at -1.051 -0.65 90)
			(size 0.6 0.6)
			(layers "F.Cu" "F.Mask" "F.Paste")
			(net 1300 "/USER_IO.LED_GREEN1")
			(pinfunction "G")
			(pintype "passive")
		)
		(pad "2" smd rect
			(at -1.051 0.65 90)
			(size 0.6 0.6)
			(layers "F.Cu" "F.Mask" "F.Paste")
			(net 1 "GND")
			(pinfunction "S")
			(pintype "passive")
		)
		(pad "3" smd rect
			(at 1.05 0 90)
			(size 0.6 0.6)
			(layers "F.Cu" "F.Mask" "F.Paste")
			(net 21 "Net-(D19-C)")
			(pinfunction "D")
			(pintype "passive")
		)
	)
	(footprint "antmicro-footprints:R_0402_1005Metric"
		(layer "F.Cu")
		(at 194.301 112.499 180)
		(descr "Resistor SMD 0402")
		(tags "resistor SMD 0402")
		(property "Reference" "R157"
			(at -0.799 -0.401 180)
			(layer "F.SilkS")
			(effects
				(font
					(size 0.7 0.7)
					(thickness 0.15)
				)
				(justify left bottom)
			)
		)
		(property "Value" "R_10k_0402"
			(at 0 1.4 180)
			(layer "F.Fab")
			(effects
				(font
					(size 0.7 0.7)
					(thickness 0.15)
				)
				(justify left bottom)
			)
		)
		(property "Description" "SMD Chip Resistor, 10 kohm, ± 1%, 62.5 mW, 0402 [1005 Metric], Thick Film, General Purpose"
			(at 0 0 180)
			(layer "F.Fab")
			(hide yes)
			(effects
				(font
					(size 1.27 1.27)
					(thickness 0.15)
				)
			)
		)
		(property "Author" "Antmicro"
			(at 388.602 224.998 0)
			(layer "F.Fab")
			(hide yes)
			(effects
				(font
					(size 1 1)
					(thickness 0.15)
				)
			)
		)
		(property "License" "Apache-2.0"
			(at 388.602 224.998 0)
			(layer "F.Fab")
			(hide yes)
			(effects
				(font
					(size 1 1)
					(thickness 0.15)
				)
			)
		)
		(property "MPN" "CR0402-FX-1002GLF"
			(at 388.602 224.998 0)
			(layer "F.Fab")
			(hide yes)
			(effects
				(font
					(size 1 1)
					(thickness 0.15)
				)
			)
		)
		(property "Manufacturer" "Bourns"
			(at 388.602 224.998 0)
			(layer "F.Fab")
			(hide yes)
			(effects
				(font
					(size 1 1)
					(thickness 0.15)
				)
			)
		)
		(property "Tolerance" "1%"
			(at 388.602 224.998 0)
			(layer "F.Fab")
			(hide yes)
			(effects
				(font
					(size 1 1)
					(thickness 0.15)
				)
			)
		)
		(property "Val" "10k"
			(at 388.602 224.998 0)
			(layer "F.Fab")
			(hide yes)
			(effects
				(font
					(size 1 1)
					(thickness 0.15)
				)
			)
		)
		(sheetname "USB PHY")
		(sheetfile "usb-phy.kicad_sch")
		(attr smd)
		(fp_rect
			(start -0.925 -0.47)
			(end 0.925 0.47)
			(stroke
				(width 0.05)
				(type default)
			)
			(fill no)
			(layer "F.CrtYd")
		)
		(fp_rect
			(start -0.5 -0.25)
			(end 0.5 0.25)
			(stroke
				(width 0.15)
				(type solid)
			)
			(fill no)
			(layer "F.Fab")
		)
		(pad "1" smd roundrect
			(at -0.48 0 180)
			(size 0.59 0.64)
			(layers "F.Cu" "F.Mask" "F.Paste")
			(roundrect_rratio 0.25)
			(net 496 "/FPGA Bank 12 & 13/USB_HOST.~{RESET}")
			(pintype "passive")
		)
		(pad "2" smd roundrect
			(at 0.48 0 180)
			(size 0.59 0.64)
			(layers "F.Cu" "F.Mask" "F.Paste")
			(roundrect_rratio 0.25)
			(net 24 "+3V3")
			(pintype "passive")
		)
	)
)
